(kicad_pcb
	(version 20260206)
	(generator "pcbnew")
	(generator_version "10.0")
	(general
		(thickness 1.6)
		(legacy_teardrops no)
	)
	(paper "A4")
	(title_block
		(title "netronome-mezz — pcbd0082-001_rev01_jul9_a.brd")
		(comment 1 "Open CloudServer (Microsoft) / footprints 436-439 of 714")
	)
	(layers
		(0 "F.Cu" signal "TOP")
		(4 "In1.Cu" signal "02_GND")
		(6 "In2.Cu" signal "03_SIG")
		(8 "In3.Cu" signal "04_SIG")
		(10 "In4.Cu" signal "05_GND")
		(12 "In5.Cu" signal "06_PWR1")
		(14 "In6.Cu" signal "07_SIG")
		(16 "In7.Cu" signal "08_SIG")
		(18 "In8.Cu" signal "09_GND")
		(2 "B.Cu" signal "BOTTOM")
		(9 "F.Adhes" user "F.Adhesive")
		(11 "B.Adhes" user "B.Adhesive")
		(13 "F.Paste" user "Package Geometry/Pastemask Top")
		(15 "B.Paste" user "Package Geometry/Pastemask Bottom")
		(5 "F.SilkS" user "Ref Des/Silkscreen Top")
		(7 "B.SilkS" user "Ref Des/Silkscreen Bottom")
		(1 "F.Mask" user "Board Geometry/Soldermask Top")
		(3 "B.Mask" user "Board Geometry/Soldermask Bottom")
		(17 "Dwgs.User" user "User.Drawings")
		(19 "Cmts.User" user "User.Comments")
		(21 "Eco1.User" user "User.Eco1")
		(23 "Eco2.User" user "User.Eco2")
		(25 "Edge.Cuts" user "Board Geometry/Outline")
		(27 "Margin" user)
		(31 "F.CrtYd" user "Package Geometry/Place Bound Top")
		(29 "B.CrtYd" user "Package Geometry/Place Bound Bottom")
		(35 "F.Fab" user "Ref Des/Assembly Top")
		(33 "B.Fab" user "Ref Des/Assembly Bottom")
		(45 "User.4" user "COMPVAL_TYPE_BOTTOM")
	)
	(footprint ""
		(layer "B.Cu")
		(at 67.818 40.64 90)
		(property "Reference" "U6"
			(at -4.5085 -0.508 0)
			(unlocked yes)
			(layer "B.SilkS")
			(effects
				(font
					(size 1.27 0.9652)
					(thickness 0.1524)
				)
				(justify left mirror)
			)
		)
		(property "Value" "*"
			(at 0.2921 1.813154 90)
			(unlocked yes)
			(layer "B.Fab")
			(hide yes)
			(effects
				(font
					(size 0.7874 0.5842)
					(thickness 0.2032)
				)
				(justify left mirror)
			)
		)
		(property "Device Type" "TRAN0026"
			(at 0.2921 1.813154 90)
			(unlocked yes)
			(layer "B.Fab")
			(hide yes)
			(effects
				(font
					(size 0.7874 0.5842)
					(thickness 0.2032)
				)
				(justify left mirror)
			)
		)
		(duplicate_pad_numbers_are_jumpers no)
		(fp_line
			(start 3.302 -3.302)
			(end 3.302 -2.667)
			(stroke
				(width 0.1524)
				(type default)
			)
			(layer "B.SilkS")
		)
		(fp_line
			(start 2.667 -3.302)
			(end 3.302 -3.302)
			(stroke
				(width 0.1524)
				(type default)
			)
			(layer "B.SilkS")
		)
		(fp_line
			(start -3.302 2.667)
			(end -3.302 3.302)
			(stroke
				(width 0.1524)
				(type default)
			)
			(layer "B.SilkS")
		)
		(fp_line
			(start -3.302 3.302)
			(end -2.667 3.302)
			(stroke
				(width 0.1524)
				(type default)
			)
			(layer "B.SilkS")
		)
		(fp_circle
			(center 3.81508 -2.4638)
			(end 3.81508 -2.179803)
			(stroke
				(width 0.1524)
				(type default)
			)
			(fill no)
			(layer "B.SilkS")
		)
		(fp_poly
			(pts
				(xy 0 -2.032) (xy 0 -0.127) (xy -0.889 -0.127) (xy -0.889 -2.032)
			)
			(stroke
				(width 0)
				(type default)
			)
			(fill yes)
			(layer "B.Paste")
		)
		(fp_poly
			(pts
				(xy -2.032 -2.032) (xy -2.032 -0.127) (xy -1.143 -0.127) (xy -1.143 -2.032)
			)
			(stroke
				(width 0)
				(type default)
			)
			(fill yes)
			(layer "B.Paste")
		)
		(fp_poly
			(pts
				(xy 0 2.032) (xy 0 0.127) (xy -0.889 0.127) (xy -0.889 2.032)
			)
			(stroke
				(width 0)
				(type default)
			)
			(fill yes)
			(layer "B.Paste")
		)
		(fp_poly
			(pts
				(xy -2.032 2.032) (xy -2.032 0.127) (xy -1.143 0.127) (xy -1.143 2.032)
			)
			(stroke
				(width 0)
				(type default)
			)
			(fill yes)
			(layer "B.Paste")
		)
		(fp_poly
			(pts
				(xy -3.937 -2.54) (xy -3.937 3.937) (xy 2.54 3.937) (xy 3.937 3.937) (xy 3.937 2.54) (xy 3.937 -3.937)
				(xy -2.54 -3.937) (xy -3.937 -3.937)
			)
			(stroke
				(width 0)
				(type default)
			)
			(fill no)
			(layer "B.CrtYd")
		)
		(fp_line
			(start 3.048 -3.048)
			(end 3.048 3.048)
			(stroke
				(width 0.1524)
				(type default)
			)
			(layer "B.Fab")
		)
		(fp_line
			(start -3.048 -3.048)
			(end 3.048 -3.048)
			(stroke
				(width 0.1524)
				(type default)
			)
			(layer "B.Fab")
		)
		(fp_line
			(start 3.048 3.048)
			(end -3.048 3.048)
			(stroke
				(width 0.1524)
				(type default)
			)
			(layer "B.Fab")
		)
		(fp_line
			(start -3.048 3.048)
			(end -3.048 -3.048)
			(stroke
				(width 0.1524)
				(type default)
			)
			(layer "B.Fab")
		)
		(fp_circle
			(center 2.413 -2.413)
			(end 2.413 -2.129003)
			(stroke
				(width 0.1524)
				(type default)
			)
			(fill no)
			(layer "B.Fab")
		)
		(fp_text user "40"
			(at 1.905 -4.09067 270)
			(unlocked yes)
			(layer "B.SilkS")
			(effects
				(font
					(size 0.7874 0.5842)
					(thickness 0.127)
				)
				(justify left mirror)
			)
		)
		(fp_text user "20"
			(at -2.31267 4.826 0)
			(unlocked yes)
			(layer "B.SilkS")
			(effects
				(font
					(size 0.7874 0.5842)
					(thickness 0.127)
				)
				(justify left mirror)
			)
		)
		(pad "1" smd custom
			(at 2.9464 -2.250008)
			(size 0.06985 0.06985)
			(layers "B.Cu" "B.Mask" "B.Paste")
			(net "10N2253")
			(options
				(clearance outline)
				(anchor circle)
			)
			(primitives
				(gr_poly
					(pts
						(xy -0.1397 -0.4064) (xy -0.1397 0.3302) (xy -0.0635 0.4064) (xy 0.1397 0.4064) (xy 0.1397 -0.4064)
					)
					(width 0)
					(fill yes)
				)
			)
		)
		(pad "2" smd rect
			(at 2.9464 -1.750009)
			(size 0.2794 0.8128)
			(layers "B.Cu" "B.Mask" "B.Paste")
			(net "VDD_5.0V")
		)
		(pad "3" smd rect
			(at 2.9464 -1.25001)
			(size 0.2794 0.8128)
			(layers "B.Cu" "B.Mask" "B.Paste")
			(net "10N2227")
		)
		(pad "4" smd rect
			(at 2.9464 -0.750011)
			(size 0.2794 0.8128)
			(layers "B.Cu" "B.Mask" "B.Paste")
			(net "10N2229")
		)
		(pad "5" smd rect
			(at 2.9464 -0.250012)
			(size 0.2794 0.8128)
			(layers "B.Cu" "B.Mask" "B.Paste")
			(net "GND")
		)
		(pad "6" smd rect
			(at 2.9464 0.250012)
			(size 0.2794 0.8128)
			(layers "B.Cu" "B.Mask" "B.Paste")
			(net "GH_PHASE1")
		)
		(pad "7" smd rect
			(at 2.9464 0.750011)
			(size 0.2794 0.8128)
			(layers "B.Cu" "B.Mask" "B.Paste")
			(net "10N2262")
		)
		(pad "8" smd rect
			(at 2.9464 1.25001)
			(size 0.2794 0.8128)
			(layers "B.Cu" "B.Mask" "B.Paste")
			(net "EXT_12.0V")
		)
		(pad "9" smd rect
			(at 2.9464 1.750009)
			(size 0.2794 0.8128)
			(layers "B.Cu" "B.Mask" "B.Paste")
			(net "EXT_12.0V")
		)
		(pad "10" smd custom
			(at 2.9464 2.250008)
			(size 0.06985 0.06985)
			(layers "B.Cu" "B.Mask" "B.Paste")
			(net "EXT_12.0V")
			(options
				(clearance outline)
				(anchor circle)
			)
			(primitives
				(gr_poly
					(pts
						(xy 0.1397 -0.4064) (xy 0.1397 0.3302) (xy 0.0635 0.4064) (xy -0.1397 0.4064) (xy -0.1397 -0.4064)
					)
					(width 0)
					(fill yes)
				)
			)
		)
		(pad "11" smd custom
			(at 2.250008 2.9464 270)
			(size 0.06985 0.06985)
			(layers "B.Cu" "B.Mask" "B.Paste")
			(net "EXT_12.0V")
			(options
				(clearance outline)
				(anchor circle)
			)
			(primitives
				(gr_poly
					(pts
						(xy -0.1397 -0.4064) (xy -0.1397 0.3302) (xy -0.0635 0.4064) (xy 0.1397 0.4064) (xy 0.1397 -0.4064)
					)
					(width 0)
					(fill yes)
				)
			)
		)
		(pad "12" smd rect
			(at 1.750009 2.9464 270)
			(size 0.2794 0.8128)
			(layers "B.Cu" "B.Mask" "B.Paste")
			(net "EXT_12.0V")
		)
		(pad "13" smd rect
			(at 1.25001 2.9464 270)
			(size 0.2794 0.8128)
			(layers "B.Cu" "B.Mask" "B.Paste")
			(net "EXT_12.0V")
		)
		(pad "14" smd rect
			(at 0.750011 2.9464 270)
			(size 0.2794 0.8128)
			(layers "B.Cu" "B.Mask" "B.Paste")
			(net "EXT_12.0V")
		)
		(pad "15" smd rect
			(at 0.250012 2.9464 270)
			(size 0.2794 0.8128)
			(layers "B.Cu" "B.Mask" "B.Paste")
			(net "L_1_CORE_PHASE")
		)
		(pad "16" smd rect
			(at -0.250012 2.9464 270)
			(size 0.2794 0.8128)
			(layers "B.Cu" "B.Mask" "B.Paste")
			(net "GND")
		)
		(pad "17" smd rect
			(at -0.750011 2.9464 270)
			(size 0.2794 0.8128)
			(layers "B.Cu" "B.Mask" "B.Paste")
			(net "GND")
		)
		(pad "18" smd rect
			(at -1.25001 2.9464 270)
			(size 0.2794 0.8128)
			(layers "B.Cu" "B.Mask" "B.Paste")
			(net "GND")
		)
		(pad "19" smd rect
			(at -1.750009 2.9464 270)
			(size 0.2794 0.8128)
			(layers "B.Cu" "B.Mask" "B.Paste")
			(net "GND")
		)
		(pad "20" smd custom
			(at -2.250008 2.9464 270)
			(size 0.06985 0.06985)
			(layers "B.Cu" "B.Mask" "B.Paste")
			(net "GND")
			(options
				(clearance outline)
				(anchor circle)
			)
			(primitives
				(gr_poly
					(pts
						(xy 0.1397 -0.4064) (xy 0.1397 0.3302) (xy 0.0635 0.4064) (xy -0.1397 0.4064) (xy -0.1397 -0.4064)
					)
					(width 0)
					(fill yes)
				)
			)
		)
		(pad "21" smd custom
			(at -2.9464 2.250008 180)
			(size 0.06985 0.06985)
			(layers "B.Cu" "B.Mask" "B.Paste")
			(net "GND")
			(options
				(clearance outline)
				(anchor circle)
			)
			(primitives
				(gr_poly
					(pts
						(xy -0.1397 -0.4064) (xy -0.1397 0.3302) (xy -0.0635 0.4064) (xy 0.1397 0.4064) (xy 0.1397 -0.4064)
					)
					(width 0)
					(fill yes)
				)
			)
		)
		(pad "22" smd rect
			(at -2.9464 1.750009 180)
			(size 0.2794 0.8128)
			(layers "B.Cu" "B.Mask" "B.Paste")
			(net "GND")
		)
		(pad "23" smd rect
			(at -2.9464 1.25001 180)
			(size 0.2794 0.8128)
			(layers "B.Cu" "B.Mask" "B.Paste")
			(net "GND")
		)
		(pad "24" smd rect
			(at -2.9464 0.750011 180)
			(size 0.2794 0.8128)
			(layers "B.Cu" "B.Mask" "B.Paste")
			(net "GND")
		)
		(pad "25" smd rect
			(at -2.9464 0.250012 180)
			(size 0.2794 0.8128)
			(layers "B.Cu" "B.Mask" "B.Paste")
			(net "GND")
		)
		(pad "26" smd rect
			(at -2.9464 -0.250012 180)
			(size 0.2794 0.8128)
			(layers "B.Cu" "B.Mask" "B.Paste")
			(net "GND")
		)
		(pad "27" smd rect
			(at -2.9464 -0.750011 180)
			(size 0.2794 0.8128)
			(layers "B.Cu" "B.Mask" "B.Paste")
			(net "GND")
		)
		(pad "28" smd rect
			(at -2.9464 -1.25001 180)
			(size 0.2794 0.8128)
			(layers "B.Cu" "B.Mask" "B.Paste")
			(net "GND")
		)
		(pad "29" smd rect
			(at -2.9464 -1.750009 180)
			(size 0.2794 0.8128)
			(layers "B.Cu" "B.Mask" "B.Paste")
			(net "L_1_CORE_PHASE")
		)
		(pad "30" smd custom
			(at -2.9464 -2.250008 180)
			(size 0.06985 0.06985)
			(layers "B.Cu" "B.Mask" "B.Paste")
			(net "L_1_CORE_PHASE")
			(options
				(clearance outline)
				(anchor circle)
			)
			(primitives
				(gr_poly
					(pts
						(xy 0.1397 -0.4064) (xy 0.1397 0.3302) (xy 0.0635 0.4064) (xy -0.1397 0.4064) (xy -0.1397 -0.4064)
					)
					(width 0)
					(fill yes)
				)
			)
		)
		(pad "31" smd custom
			(at -2.250008 -2.9464 90)
			(size 0.06985 0.06985)
			(layers "B.Cu" "B.Mask" "B.Paste")
			(net "L_1_CORE_PHASE")
			(options
				(clearance outline)
				(anchor circle)
			)
			(primitives
				(gr_poly
					(pts
						(xy -0.1397 -0.4064) (xy -0.1397 0.3302) (xy -0.0635 0.4064) (xy 0.1397 0.4064) (xy 0.1397 -0.4064)
					)
					(width 0)
					(fill yes)
				)
			)
		)
		(pad "32" smd rect
			(at -1.750009 -2.9464 90)
			(size 0.2794 0.8128)
			(layers "B.Cu" "B.Mask" "B.Paste")
			(net "L_1_CORE_PHASE")
		)
		(pad "33" smd rect
			(at -1.25001 -2.9464 90)
			(size 0.2794 0.8128)
			(layers "B.Cu" "B.Mask" "B.Paste")
			(net "L_1_CORE_PHASE")
		)
		(pad "34" smd rect
			(at -0.750011 -2.9464 90)
			(size 0.2794 0.8128)
			(layers "B.Cu" "B.Mask" "B.Paste")
			(net "L_1_CORE_PHASE")
		)
		(pad "35" smd rect
			(at -0.250012 -2.9464 90)
			(size 0.2794 0.8128)
			(layers "B.Cu" "B.Mask" "B.Paste")
			(net "L_1_CORE_PHASE")
		)
		(pad "36" smd rect
			(at 0.250012 -2.9464 90)
			(size 0.2794 0.8128)
			(layers "B.Cu" "B.Mask" "B.Paste")
			(net "GL_PHASE1")
		)
		(pad "37" smd rect
			(at 0.750011 -2.9464 90)
			(size 0.2794 0.8128)
			(layers "B.Cu" "B.Mask" "B.Paste")
			(net "GND")
		)
		(pad "38" smd rect
			(at 1.25001 -2.9464 90)
			(size 0.2794 0.8128)
			(layers "B.Cu" "B.Mask" "B.Paste")
			(net "CORE_FB_PH1_THERM_L")
		)
		(pad "39" smd rect
			(at 1.750009 -2.9464 90)
			(size 0.2794 0.8128)
			(layers "B.Cu" "B.Mask" "B.Paste")
			(net "10N2230")
		)
		(pad "40" smd custom
			(at 2.250008 -2.9464 90)
			(size 0.06985 0.06985)
			(layers "B.Cu" "B.Mask" "B.Paste")
			(net "NFP_CORE_PWM1")
			(options
				(clearance outline)
				(anchor circle)
			)
			(primitives
				(gr_poly
					(pts
						(xy 0.1397 -0.4064) (xy 0.1397 0.3302) (xy 0.0635 0.4064) (xy -0.1397 0.4064) (xy -0.1397 -0.4064)
					)
					(width 0)
					(fill yes)
				)
			)
		)
		(pad "41" smd rect
			(at 1.4478 -1.1938 270)
			(size 1.4986 2.0066)
			(layers "B.Cu" "B.Mask" "B.Paste")
			(net "GND")
		)
		(pad "42" smd rect
			(at 1.4478 1.1938 270)
			(size 1.4986 2.0066)
			(layers "B.Cu" "B.Mask" "B.Paste")
			(net "EXT_12.0V")
		)
		(pad "43" smd rect
			(at -1.0033 0 270)
			(size 2.3876 4.3942)
			(layers "B.Cu" "B.Mask" "B.Paste")
			(net "L_1_CORE_PHASE")
		)
		(zone
			(layer "B.Cu")
			(hatch none 0.5)
			(connect_pads
				(clearance 0)
			)
			(min_thickness 0.25)
			(keepout
				(tracks allowed)
				(vias not_allowed)
				(pads allowed)
				(copperpour not_allowed)
				(footprints allowed)
			)
			(placement
				(enabled no)
				(sheetname "")
			)
			(fill
				(thermal_gap 0.5)
				(thermal_bridge_width 0.5)
				(island_removal_mode 0)
			)
			(polygon
				(pts
					(arc
						(start 65.714397 36.82492)
						(mid 64.994003 36.82492)
						(end 65.714397 36.82492)
					)
				)
			)
		)
	)
	(footprint ""
		(layer "B.Cu")
		(at 36.7538 33.274 -90)
		(property "Reference" "R178"
			(at 0.28067 -4.2672 0)
			(unlocked yes)
			(layer "B.SilkS")
			(effects
				(font
					(size 0.7874 0.5842)
					(thickness 0.127)
				)
				(justify left mirror)
			)
		)
		(property "Value" "0"
			(at 0.148158 1.3462 180)
			(unlocked yes)
			(layer "B.Fab")
			(hide yes)
			(effects
				(font
					(size 1.27 0.9652)
					(thickness 0.000001)
				)
				(justify left mirror)
			)
		)
		(property "Device Type" "REST1111"
			(at 0.148158 1.3462 180)
			(unlocked yes)
			(layer "B.Fab")
			(hide yes)
			(effects
				(font
					(size 1.27 0.9652)
					(thickness 0.000001)
				)
				(justify left mirror)
			)
		)
		(duplicate_pad_numbers_are_jumpers no)
		(fp_poly
			(pts
				(xy -0.635 1.0668) (xy -0.635 -1.0668) (xy 0.635 -1.0668) (xy 0.635 1.0668)
			)
			(stroke
				(width 0)
				(type default)
			)
			(fill no)
			(layer "B.CrtYd")
		)
		(fp_line
			(start -0.254 0.508)
			(end 0.254 0.508)
			(stroke
				(width 0.0254)
				(type default)
			)
			(layer "B.Fab")
		)
		(fp_line
			(start 0.254 0.508)
			(end 0.254 -0.508)
			(stroke
				(width 0.0254)
				(type default)
			)
			(layer "B.Fab")
		)
		(fp_line
			(start -0.254 -0.508)
			(end -0.254 0.508)
			(stroke
				(width 0.0254)
				(type default)
			)
			(layer "B.Fab")
		)
		(fp_line
			(start 0.254 -0.508)
			(end -0.254 -0.508)
			(stroke
				(width 0.0254)
				(type default)
			)
			(layer "B.Fab")
		)
		(pad "1" smd rect
			(at 0 -0.4191 90)
			(size 0.508 0.5334)
			(layers "B.Cu" "B.Mask" "B.Paste")
			(net "NFP_CORE_VID7")
		)
		(pad "2" smd rect
			(at 0 0.4191 90)
			(size 0.508 0.5334)
			(layers "B.Cu" "B.Mask" "B.Paste")
			(net "_NFP_CORE_VID7")
		)
		(zone
			(layer "B.Cu")
			(hatch none 0.5)
			(connect_pads
				(clearance 0)
			)
			(min_thickness 0.25)
			(keepout
				(tracks not_allowed)
				(vias allowed)
				(pads allowed)
				(copperpour not_allowed)
				(footprints allowed)
			)
			(placement
				(enabled no)
				(sheetname "")
			)
			(fill
				(thermal_gap 0.5)
				(thermal_bridge_width 0.5)
				(island_removal_mode 0)
			)
			(polygon
				(pts
					(xy 36.7792 33.2486) (xy 36.7284 33.2486) (xy 36.7284 33.2994) (xy 36.7792 33.2994)
				)
			)
		)
	)
	(footprint ""
		(layer "B.Cu")
		(at 2.794 6.604)
		(property "Reference" "TP29"
			(at 0.254 -1.49733 0)
			(unlocked yes)
			(layer "B.SilkS")
			(effects
				(font
					(size 0.7874 0.5842)
					(thickness 0.127)
				)
				(justify left mirror)
			)
		)
		(property "Value" "*"
			(at 0.4826 -0.14732 0)
			(unlocked yes)
			(layer "B.Fab")
			(hide yes)
			(effects
				(font
					(size 1.27 0.9652)
					(thickness 0.000001)
				)
				(justify left mirror)
			)
		)
		(property "Device Type" "TP_SMALL"
			(at 0.4826 -0.14732 0)
			(unlocked yes)
			(layer "B.Fab")
			(hide yes)
			(effects
				(font
					(size 1.27 0.9652)
					(thickness 0.000001)
				)
				(justify left mirror)
			)
		)
		(duplicate_pad_numbers_are_jumpers no)
		(fp_line
			(start -0.8636 -0.8636)
			(end 0.8636 -0.8636)
			(stroke
				(width 0.1524)
				(type default)
			)
			(layer "B.SilkS")
		)
		(fp_line
			(start -0.8636 0.8636)
			(end -0.8636 -0.8636)
			(stroke
				(width 0.1524)
				(type default)
			)
			(layer "B.SilkS")
		)
		(fp_line
			(start 0.8636 -0.8636)
			(end 0.8636 0.8636)
			(stroke
				(width 0.1524)
				(type default)
			)
			(layer "B.SilkS")
		)
		(fp_line
			(start 0.8636 0.8636)
			(end -0.8636 0.8636)
			(stroke
				(width 0.1524)
				(type default)
			)
			(layer "B.SilkS")
		)
		(fp_poly
			(pts
				(xy 0.635 -0.635) (xy 0.635 0.635) (xy -0.635 0.635) (xy -0.635 -0.635)
			)
			(stroke
				(width 0)
				(type default)
			)
			(fill no)
			(layer "B.CrtYd")
		)
		(pad "1" smd rect
			(at 0 0 180)
			(size 1.27 1.27)
			(layers "B.Cu" "B.Mask" "B.Paste")
			(net "PGRM_JTAG_TDO")
		)
	)
	(footprint ""
		(layer "B.Cu")
		(at 22.733 31.75 -90)
		(property "Reference" "R59"
			(at -0.10033 0.889 0)
			(unlocked yes)
			(layer "B.SilkS")
			(effects
				(font
					(size 0.7874 0.5842)
					(thickness 0.127)
				)
				(justify left mirror)
			)
		)
		(property "Value" "4.75K"
			(at 0.148158 1.3462 180)
			(unlocked yes)
			(layer "B.Fab")
			(hide yes)
			(effects
				(font
					(size 1.27 0.9652)
					(thickness 0.000001)
				)
				(justify left mirror)
			)
		)
		(property "Device Type" "REST4024"
			(at 0.148158 1.3462 180)
			(unlocked yes)
			(layer "B.Fab")
			(hide yes)
			(effects
				(font
					(size 1.27 0.9652)
					(thickness 0.000001)
				)
				(justify left mirror)
			)
		)
		(duplicate_pad_numbers_are_jumpers no)
		(fp_poly
			(pts
				(xy -0.635 1.0668) (xy -0.635 -1.0668) (xy 0.635 -1.0668) (xy 0.635 1.0668)
			)
			(stroke
				(width 0)
				(type default)
			)
			(fill no)
			(layer "B.CrtYd")
		)
		(fp_line
			(start -0.254 0.508)
			(end 0.254 0.508)
			(stroke
				(width 0.0254)
				(type default)
			)
			(layer "B.Fab")
		)
		(fp_line
			(start 0.254 0.508)
			(end 0.254 -0.508)
			(stroke
				(width 0.0254)
				(type default)
			)
			(layer "B.Fab")
		)
		(fp_line
			(start -0.254 -0.508)
			(end -0.254 0.508)
			(stroke
				(width 0.0254)
				(type default)
			)
			(layer "B.Fab")
		)
		(fp_line
			(start 0.254 -0.508)
			(end -0.254 -0.508)
			(stroke
				(width 0.0254)
				(type default)
			)
			(layer "B.Fab")
		)
		(pad "1" smd rect
			(at 0 -0.4191 90)
			(size 0.508 0.5334)
			(layers "B.Cu" "B.Mask" "B.Paste")
			(net "9N2032")
		)
		(pad "2" smd rect
			(at 0 0.4191 90)
			(size 0.508 0.5334)
			(layers "B.Cu" "B.Mask" "B.Paste")
			(net "GND")
		)
		(zone
			(layer "B.Cu")
			(hatch none 0.5)
			(connect_pads
				(clearance 0)
			)
			(min_thickness 0.25)
			(keepout
				(tracks not_allowed)
				(vias allowed)
				(pads allowed)
				(copperpour not_allowed)
				(footprints allowed)
			)
			(placement
				(enabled no)
				(sheetname "")
			)
			(fill
				(thermal_gap 0.5)
				(thermal_bridge_width 0.5)
				(island_removal_mode 0)
			)
			(polygon
				(pts
					(xy 22.7584 31.7246) (xy 22.7076 31.7246) (xy 22.7076 31.7754) (xy 22.7584 31.7754)
				)
			)
		)
	)
)
